# BASEBOARD_FAB2 (Tioga Pass) — schematic parts with pin connectivity, parts 2403–2403 of 4751; source: Cadence DE-HDL packaged netlist (pstxprt.dat, pstxnet.dat, pstchip.dat)

J9U1  SCONN288_H44441003  SCONN  pkg PIP  page 80
  1  \12v\(1)  = P12V_NVDIMM_GHJ
  2  VSS(93)  GROUND  = GND
  3  DQ(4)  BI  = M_H_DQ<4>
  4  VSS(92)  GROUND  = GND
  5  DQ(0)  BI  = M_H_DQ<0>
  6  VSS(91)  GROUND  = GND
  7  DQS9P  BI  = M_H_DQS_DP<9>
  8  DQS9N  BI  = M_H_DQS_DN<9>
  9  VSS(90)  GROUND  = GND
  10  DQ(6)  BI  = M_H_DQ<6>
  11  VSS(89)  GROUND  = GND
  12  DQ(2)  BI  = M_H_DQ<2>
  13  VSS(88)  GROUND  = GND
  14  DQ(12)  BI  = M_H_DQ<12>
  15  VSS(87)  GROUND  = GND
  16  DQ(8)  BI  = M_H_DQ<8>
  17  VSS(86)  GROUND  = GND
  18  DQS10P  BI  = M_H_DQS_DP<10>
  19  DQS10N  BI  = M_H_DQS_DN<10>
  20  VSS(85)  GROUND  = GND
  21  DQ(14)  BI  = M_H_DQ<14>
  22  VSS(84)  GROUND  = GND
  23  DQ(10)  BI  = M_H_DQ<10>
  24  VSS(83)  GROUND  = GND
  25  DQ(20)  BI  = M_H_DQ<20>
  26  VSS(82)  GROUND  = GND
  27  DQ(16)  BI  = M_H_DQ<16>
  28  VSS(81)  GROUND  = GND
  29  DQS11P  BI  = M_H_DQS_DP<11>
  30  DQS11N  BI  = M_H_DQS_DN<11>
  31  VSS(80)  GROUND  = GND
  32  DQ(22)  BI  = M_H_DQ<22>
  33  VSS(79)  GROUND  = GND
  34  DQ(18)  BI  = M_H_DQ<18>
  35  VSS(78)  GROUND  = GND
  36  DQ(28)  BI  = M_H_DQ<28>
  37  VSS(77)  GROUND  = GND
  38  DQ(24)  BI  = M_H_DQ<24>
  39  VSS(76)  GROUND  = GND
  40  DQS12P  BI  = M_H_DQS_DP<12>
  41  DQS12N  BI  = M_H_DQS_DN<12>
  42  VSS(75)  GROUND  = GND
  43  DQ(30)  BI  = M_H_DQ<30>
  44  VSS(74)  GROUND  = GND
  45  DQ(26)  BI  = M_H_DQ<26>
  46  VSS(73)  GROUND  = GND
  47  CB(4)  BI  = M_H_ECC<4>
  48  VSS(72)  GROUND  = GND
  49  CB(0)  BI  = M_H_ECC<0>
  50  VSS(71)  GROUND  = GND
  51  DQS17P  BI  = M_H_DQS_DP<17>
  52  DQS17N  BI  = M_H_DQS_DN<17>
  53  VSS(70)  GROUND  = GND
  54  CB(6)  BI  = M_H_ECC<6>
  55  VSS(69)  GROUND  = GND
  56  CB(2)  BI  = M_H_ECC<2>
  57  VSS(68)  GROUND  = GND
  58  RESET_N  BI  = M_GHJ_RST_N
  59  VDD(25)  POWER  = PVDDQ_GHJ
  60  CKE(0)  BI  = M_H_CKE<2>
  61  VDD(24)  POWER  = PVDDQ_GHJ
  62  ACT_N  BI  = M_H_ACT_N
  63  BG(0)  BI  = M_H_BG<0>
  64  VDD(23)  POWER  = PVDDQ_GHJ
  65  A12  BI  = M_H_MA<12>
  66  A9  BI  = M_H_MA<9>
  67  VDD(22)  POWER  = PVDDQ_GHJ
  68  A8  BI  = M_H_MA<8>
  69  A6  BI  = M_H_MA<6>
  70  VDD(21)  POWER  = PVDDQ_GHJ
  71  A3  BI  = M_H_MA<3>
  72  A1  BI  = M_H_MA<1>
  73  VDD(20)  POWER  = PVDDQ_GHJ
  74  CK0P  BI  = M_H_CLK_DP<2>
  75  CK0N  BI  = M_H_CLK_DN<2>
  76  VDD(19)  POWER  = PVDDQ_GHJ
  77  VTT(1)  POWER  = PVTT_GHJ
  78  EVENT_N  BI  = FM_DIMM_EVENT_COD_N
  79  A0  BI  = M_H_MA<0>
  80  VDD(18)  POWER  = PVDDQ_GHJ
  81  BA(0)  BI  = M_H_BA<0>
  82  A16_RAS_N  BI  = M_H_MA<16>
  83  VDD(17)  POWER  = PVDDQ_GHJ
  84  S0_N  BI  = M_H_CS_N<4>
  85  VDD(16)  POWER  = PVDDQ_GHJ
  86  A15_CAS_N  BI  = M_H_MA<15>
  87  ODT(0)  BI  = M_H_ODT<2>
  88  VDD(15)  POWER  = PVDDQ_GHJ
  89  S1_N  BI  = M_H_CS_N<5>
  90  VDD(14)  POWER  = PVDDQ_GHJ
  91  ODT(1)  BI  = M_H_ODT<3>
  92  VDD(13)  POWER  = PVDDQ_GHJ
  93  S2_N_C(0)  BI  = M_H_CS_N<6>
  94  VSS(67)  GROUND  = GND
  95  DQ(36)  BI  = M_H_DQ<36>
  96  VSS(66)  GROUND  = GND
  97  DQ(32)  BI  = M_H_DQ<32>
  98  VSS(65)  GROUND  = GND
  99  DQS13P  BI  = M_H_DQS_DP<13>
  100  DQS13N  BI  = M_H_DQS_DN<13>
  101  VSS(64)  GROUND  = GND
  102  DQ(38)  BI  = M_H_DQ<38>
  103  VSS(63)  GROUND  = GND
  104  DQ(34)  BI  = M_H_DQ<34>
  105  VSS(62)  GROUND  = GND
  106  DQ(44)  BI  = M_H_DQ<44>
  107  VSS(61)  GROUND  = GND
  108  DQ(40)  BI  = M_H_DQ<40>
  109  VSS(60)  GROUND  = GND
  110  DQS14P  BI  = M_H_DQS_DP<14>
  111  DQS14N  BI  = M_H_DQS_DN<14>
  112  VSS(59)  GROUND  = GND
  113  DQ(46)  BI  = M_H_DQ<46>
  114  VSS(58)  GROUND  = GND
  115  DQ(42)  BI  = M_H_DQ<42>
  116  VSS(57)  GROUND  = GND
  117  DQ(52)  BI  = M_H_DQ<52>
  118  VSS(56)  GROUND  = GND
  119  DQ(48)  BI  = M_H_DQ<48>
  120  VSS(55)  GROUND  = GND
  121  DQS15P  BI  = M_H_DQS_DP<15>
  122  DQS15N  BI  = M_H_DQS_DN<15>
  123  VSS(54)  GROUND  = GND
  124  DQ(54)  BI  = M_H_DQ<54>
  125  VSS(53)  GROUND  = GND
  126  DQ(50)  BI  = M_H_DQ<50>
  127  VSS(52)  GROUND  = GND
  128  DQ(60)  BI  = M_H_DQ<60>
  129  VSS(51)  GROUND  = GND
  130  DQ(56)  BI  = M_H_DQ<56>
  131  VSS(50)  GROUND  = GND
  132  DQS16P  BI  = M_H_DQS_DP<16>
  133  DQS16N  BI  = M_H_DQS_DN<16>
  134  VSS(49)  GROUND  = GND
  135  DQ(62)  BI  = M_H_DQ<62>
  136  VSS(48)  GROUND  = GND
  137  DQ(58)  BI  = M_H_DQ<58>
  138  VSS(47)  GROUND  = GND
  139  SA(0)  BI  = PVPP_GHJ
  140  SA(1)  BI  = PVPP_GHJ
  141  SCL  BI  = SMB_DDR_GHJ_VPP_SCL
  142  VPP(4)  POWER  = PVPP_GHJ
  143  VPP(3)  POWER  = PVPP_GHJ
  144  RFU(2)  BI  = TP_CH_H_DIMM0_RFU_2
  145  \12v\(0)  = P12V_NVDIMM_GHJ
  146  VREFCA  BI  = M_H_VREF
  147  VSS(46)  GROUND  = GND
  148  DQ(5)  BI  = M_H_DQ<5>
  149  VSS(45)  GROUND  = GND
  150  DQ(1)  BI  = M_H_DQ<1>
  151  VSS(44)  GROUND  = GND
  152  DQS0N  BI  = M_H_DQS_DN<0>
  153  DQS0P  BI  = M_H_DQS_DP<0>
  154  VSS(43)  GROUND  = GND
  155  DQ(7)  BI  = M_H_DQ<7>
  156  VSS(42)  GROUND  = GND
  157  DQ(3)  BI  = M_H_DQ<3>
  158  VSS(41)  GROUND  = GND
  159  DQ(13)  BI  = M_H_DQ<13>
  160  VSS(40)  GROUND  = GND
  161  DQ(9)  BI  = M_H_DQ<9>
  162  VSS(39)  GROUND  = GND
  163  DQS1N  BI  = M_H_DQS_DN<1>
  164  DQS1P  BI  = M_H_DQS_DP<1>
  165  VSS(38)  GROUND  = GND
  166  DQ(15)  BI  = M_H_DQ<15>
  167  VSS(37)  GROUND  = GND
  168  DQ(11)  BI  = M_H_DQ<11>
  169  VSS(36)  GROUND  = GND
  170  DQ(21)  BI  = M_H_DQ<21>
  171  VSS(35)  GROUND  = GND
  172  DQ(17)  BI  = M_H_DQ<17>
  173  VSS(34)  GROUND  = GND
  174  DQS2N  BI  = M_H_DQS_DN<2>
  175  DQS2P  BI  = M_H_DQS_DP<2>
  176  VSS(33)  GROUND  = GND
  177  DQ(23)  BI  = M_H_DQ<23>
  178  VSS(32)  GROUND  = GND
  179  DQ(19)  BI  = M_H_DQ<19>
  180  VSS(31)  GROUND  = GND
  181  DQ(29)  BI  = M_H_DQ<29>
  182  VSS(30)  GROUND  = GND
  183  DQ(25)  BI  = M_H_DQ<25>
  184  VSS(29)  GROUND  = GND
  185  DQS3N  BI  = M_H_DQS_DN<3>
  186  DQS3P  BI  = M_H_DQS_DP<3>
  187  VSS(28)  GROUND  = GND
  188  DQ(31)  BI  = M_H_DQ<31>
  189  VSS(27)  GROUND  = GND
  190  DQ(27)  BI  = M_H_DQ<27>
  191  VSS(26)  GROUND  = GND
  192  CB(5)  BI  = M_H_ECC<5>
  193  VSS(25)  GROUND  = GND
  194  CB(1)  BI  = M_H_ECC<1>
  195  VSS(24)  GROUND  = GND
  196  DQS8N  BI  = M_H_DQS_DN<8>
  197  DQS8P  BI  = M_H_DQS_DP<8>
  198  VSS(23)  GROUND  = GND
  199  CB(7)  BI  = M_H_ECC<7>
  200  VSS(22)  GROUND  = GND
  201  CB(3)  BI  = M_H_ECC<3>
  202  VSS(21)  GROUND  = GND
  203  CKE(1)  BI  = M_H_CKE<3>
  204  VDD(12)  POWER  = PVDDQ_GHJ
  205  RFU(0)  BI  = TP_CH_H_DIMM0_RFU_0
  206  VDD(11)  POWER  = PVDDQ_GHJ
  207  BG(1)  BI  = M_H_BG<1>
  208  ALERT_N  BI  = M_H_ALERT_N
  209  VDD(10)  POWER  = PVDDQ_GHJ
  210  A11  BI  = M_H_MA<11>
  211  A7  BI  = M_H_MA<7>
  212  VDD(9)  POWER  = PVDDQ_GHJ
  213  A5  BI  = M_H_MA<5>
  214  A4  BI  = M_H_MA<4>
  215  VDD(8)  POWER  = PVDDQ_GHJ
  216  A2  BI  = M_H_MA<2>
  217  VDD(7)  POWER  = PVDDQ_GHJ
  218  CK1P  BI  = M_H_CLK_DP<3>
  219  CK1N  BI  = M_H_CLK_DN<3>
  220  VDD(6)  POWER  = PVDDQ_GHJ
  221  VTT(0)  POWER  = PVTT_GHJ
  222  PAR  BI  = M_H_PAR
  223  VDD(5)  POWER  = PVDDQ_GHJ
  224  BA(1)  BI  = M_H_BA<1>
  225  A10  BI  = M_H_MA<10>
  226  VDD(4)  POWER  = PVDDQ_GHJ
  227  RFU(1)  BI  = TP_CH_H_DIMM0_RFU_1
  228  A14_WE_N  BI  = M_H_MA<14>
  229  VDD(3)  POWER  = PVDDQ_GHJ
  230  SAVE_N_NC  BI  = FM_ADR_COMPLETE_GHJ_N
  231  VDD(2)  POWER  = PVDDQ_GHJ
  232  A13  BI  = M_H_MA<13>
  233  VDD(1)  POWER  = PVDDQ_GHJ
  234  A17  BI  = M_H_MA<17>
  235  C(2)  BI  = M_H_C<2>
  236  VDD(0)  POWER  = PVDDQ_GHJ
  237  S3_N_C(1)  BI  = M_H_CS_N<7>
  238  SA(2)  BI  = GND
  239  VSS(20)  GROUND  = GND
  240  DQ(37)  BI  = M_H_DQ<37>
  241  VSS(19)  GROUND  = GND
  242  DQ(33)  BI  = M_H_DQ<33>
  243  VSS(18)  GROUND  = GND
  244  DQS4N  BI  = M_H_DQS_DN<4>
  245  DQS4P  BI  = M_H_DQS_DP<4>
  246  VSS(17)  GROUND  = GND
  247  DQ(39)  BI  = M_H_DQ<39>
  248  VSS(16)  GROUND  = GND
  249  DQ(35)  BI  = M_H_DQ<35>
  250  VSS(15)  GROUND  = GND
  251  DQ(45)  BI  = M_H_DQ<45>
  252  VSS(14)  GROUND  = GND
  253  DQ(41)  BI  = M_H_DQ<41>
  254  VSS(13)  GROUND  = GND
  255  DQS5N  BI  = M_H_DQS_DN<5>
  256  DQS5P  BI  = M_H_DQS_DP<5>
  257  VSS(12)  GROUND  = GND
  258  DQ(47)  BI  = M_H_DQ<47>
  259  VSS(11)  GROUND  = GND
  260  DQ(43)  BI  = M_H_DQ<43>
  261  VSS(10)  GROUND  = GND
  262  DQ(53)  BI  = M_H_DQ<53>
  263  VSS(9)  GROUND  = GND
  264  DQ(49)  BI  = M_H_DQ<49>
  265  VSS(8)  GROUND  = GND
  266  DQS6N  BI  = M_H_DQS_DN<6>
  267  DQS6P  BI  = M_H_DQS_DP<6>
  268  VSS(7)  GROUND  = GND
  269  DQ(55)  BI  = M_H_DQ<55>
  270  VSS(6)  GROUND  = GND
  271  DQ(51)  BI  = M_H_DQ<51>
  272  VSS(5)  GROUND  = GND
  273  DQ(61)  BI  = M_H_DQ<61>
  274  VSS(4)  GROUND  = GND
  275  DQ(57)  BI  = M_H_DQ<57>
  276  VSS(3)  GROUND  = GND
  277  DQS7N  BI  = M_H_DQS_DN<7>
  278  DQS7P  BI  = M_H_DQS_DP<7>
  279  VSS(2)  GROUND  = GND
  280  DQ(63)  BI  = M_H_DQ<63>
  281  VSS(1)  GROUND  = GND
  282  DQ(59)  BI  = M_H_DQ<59>
  283  VSS(0)  GROUND  = GND
  284  VDDSPD  BI  = PVPP_GHJ
  285  SDA  BI  = SMB_DDR_GHJ_VPP_SDA
  286  VPP(1)  POWER  = PVPP_GHJ
  287  VPP(0)  POWER  = PVPP_GHJ
  288  VPP(2)  POWER  = PVPP_GHJ
